(kicad_pcb
	(version 20260206)
	(generator "pcbnew")
	(generator_version "10.0")
	(general
		(thickness 1.6)
		(legacy_teardrops no)
	)
	(paper "A4")
	(title_block
		(title "Bryce Canyon_R.DPB_16317-1_OCP.brd")
		(comment 1 "Bryce Canyon / footprints 760-766 of 2099")
	)
	(layers
		(0 "F.Cu" signal "TOP")
		(4 "In1.Cu" signal "L2GND")
		(6 "In2.Cu" signal "L3")
		(8 "In3.Cu" signal "L4VCC")
		(10 "In4.Cu" signal "L5VCC")
		(12 "In5.Cu" signal "L6")
		(14 "In6.Cu" signal "L7GND")
		(2 "B.Cu" signal "BOTTOM")
		(9 "F.Adhes" user "F.Adhesive")
		(11 "B.Adhes" user "B.Adhesive")
		(13 "F.Paste" user "Package Geometry/Pastemask Top")
		(15 "B.Paste" user "Package Geometry/Pastemask Bottom")
		(5 "F.SilkS" user "Ref Des/Silkscreen Top")
		(7 "B.SilkS" user "Ref Des/Silkscreen Bottom")
		(1 "F.Mask" user "Board Geometry/Soldermask Top")
		(3 "B.Mask" user "Board Geometry/Soldermask Bottom")
		(17 "Dwgs.User" user "User.Drawings")
		(19 "Cmts.User" user "User.Comments")
		(21 "Eco1.User" user "User.Eco1")
		(23 "Eco2.User" user "User.Eco2")
		(25 "Edge.Cuts" user "Board Geometry/Outline")
		(27 "Margin" user)
		(31 "F.CrtYd" user "Package Geometry/Place Bound Top")
		(29 "B.CrtYd" user "Package Geometry/Place Bound Bottom")
		(35 "F.Fab" user "Ref Des/Assembly Top")
		(33 "B.Fab" user "Ref Des/Assembly Bottom")
	)
	(footprint ""
		(layer "F.Cu")
		(at 339.743796 -99.860354 90)
		(property "Reference" "Q266"
			(at 0 0 90)
			(layer "F.SilkS")
			(hide yes)
			(effects
				(font
					(size 1.27 1.27)
				)
			)
		)
		(property "Value" "SSM3K324R-GP"
			(at 0.127 -8.9662 90)
			(unlocked yes)
			(layer "F.Fab")
			(hide yes)
			(effects
				(font
					(size 1.016 1.016)
					(thickness 0.1524)
				)
			)
		)
		(property "Device Type" "SOT23DGS2D4H35"
			(at 0.127 -10.4902 90)
			(unlocked yes)
			(layer "F.Fab")
			(hide yes)
			(effects
				(font
					(size 1.016 1.016)
					(thickness 0.1524)
				)
			)
		)
		(duplicate_pad_numbers_are_jumpers no)
		(fp_line
			(start 1.651 -1.778)
			(end -1.651 -1.778)
			(stroke
				(width 0.1524)
				(type default)
			)
			(layer "F.SilkS")
		)
		(fp_line
			(start -1.651 -1.778)
			(end -1.651 1.778)
			(stroke
				(width 0.1524)
				(type default)
			)
			(layer "F.SilkS")
		)
		(fp_line
			(start 1.651 1.778)
			(end 1.651 -1.778)
			(stroke
				(width 0.1524)
				(type default)
			)
			(layer "F.SilkS")
		)
		(fp_line
			(start -1.651 1.778)
			(end 1.651 1.778)
			(stroke
				(width 0.1524)
				(type default)
			)
			(layer "F.SilkS")
		)
		(fp_poly
			(pts
				(xy -1.778 1.8796) (xy -1.778 -1.8796) (xy 1.778 -1.8796) (xy 1.778 1.8796)
			)
			(stroke
				(width 0)
				(type default)
			)
			(fill no)
			(layer "F.CrtYd")
		)
		(fp_poly
			(pts
				(xy -1.778 1.8796) (xy -1.778 -1.8796) (xy 1.778 -1.8796) (xy 1.778 1.8796)
			)
			(stroke
				(width 0)
				(type default)
			)
			(fill no)
			(layer "F.Fab")
		)
		(pad "D" smd custom
			(at 0 -0.9525 90)
			(size 0.1905 0.1905)
			(layers "F.Cu" "F.Mask" "F.Paste")
			(net "DRV_ACT_19_N")
			(options
				(clearance outline)
				(anchor circle)
			)
			(primitives
				(gr_poly
					(pts
						(arc
							(start -0.1778 0.5715)
							(mid -0.321484 0.511984)
							(end -0.381 0.3683)
						)
						(arc
							(start -0.381 -0.3683)
							(mid -0.321484 -0.511984)
							(end -0.1778 -0.5715)
						)
						(arc
							(start 0.1778 -0.5715)
							(mid 0.321484 -0.511984)
							(end 0.381 -0.3683)
						)
						(arc
							(start 0.381 0.3683)
							(mid 0.321484 0.511984)
							(end 0.1778 0.5715)
						)
					)
					(width 0)
					(fill yes)
				)
			)
		)
		(pad "G" smd custom
			(at -0.98425 0.9525 90)
			(size 0.1905 0.1905)
			(layers "F.Cu" "F.Mask" "F.Paste")
			(net "DRIVE_B_19_ACT")
			(options
				(clearance outline)
				(anchor circle)
			)
			(primitives
				(gr_poly
					(pts
						(arc
							(start -0.1778 0.5715)
							(mid -0.321484 0.511984)
							(end -0.381 0.3683)
						)
						(arc
							(start -0.381 -0.3683)
							(mid -0.321484 -0.511984)
							(end -0.1778 -0.5715)
						)
						(arc
							(start 0.1778 -0.5715)
							(mid 0.321484 -0.511984)
							(end 0.381 -0.3683)
						)
						(arc
							(start 0.381 0.3683)
							(mid 0.321484 0.511984)
							(end 0.1778 0.5715)
						)
					)
					(width 0)
					(fill yes)
				)
			)
		)
		(pad "S" smd custom
			(at 0.98425 0.9525 90)
			(size 0.1905 0.1905)
			(layers "F.Cu" "F.Mask" "F.Paste")
			(net "GND")
			(options
				(clearance outline)
				(anchor circle)
			)
			(primitives
				(gr_poly
					(pts
						(arc
							(start -0.1778 0.5715)
							(mid -0.321484 0.511984)
							(end -0.381 0.3683)
						)
						(arc
							(start -0.381 -0.3683)
							(mid -0.321484 -0.511984)
							(end -0.1778 -0.5715)
						)
						(arc
							(start 0.1778 -0.5715)
							(mid 0.321484 -0.511984)
							(end 0.381 -0.3683)
						)
						(arc
							(start 0.381 0.3683)
							(mid 0.321484 0.511984)
							(end 0.1778 0.5715)
						)
					)
					(width 0)
					(fill yes)
				)
			)
		)
	)
	(footprint ""
		(layer "F.Cu")
		(at 261.915402 -372.907814 180)
		(property "Reference" "Q209"
			(at 0 0 180)
			(layer "F.SilkS")
			(hide yes)
			(effects
				(font
					(size 1.27 1.27)
				)
			)
		)
		(property "Value" "2N7002K-2-GP"
			(at 0.127 -8.9662 180)
			(unlocked yes)
			(layer "F.Fab")
			(hide yes)
			(effects
				(font
					(size 1.016 1.016)
					(thickness 0.1524)
				)
			)
		)
		(property "Device Type" "SOT23DGS2D4H44"
			(at 0.127 -10.4902 180)
			(unlocked yes)
			(layer "F.Fab")
			(hide yes)
			(effects
				(font
					(size 1.016 1.016)
					(thickness 0.1524)
				)
			)
		)
		(duplicate_pad_numbers_are_jumpers no)
		(fp_line
			(start 1.651 1.778)
			(end 1.651 -1.778)
			(stroke
				(width 0.1524)
				(type default)
			)
			(layer "F.SilkS")
		)
		(fp_line
			(start 1.651 -1.778)
			(end -1.651 -1.778)
			(stroke
				(width 0.1524)
				(type default)
			)
			(layer "F.SilkS")
		)
		(fp_line
			(start -1.651 1.778)
			(end 1.651 1.778)
			(stroke
				(width 0.1524)
				(type default)
			)
			(layer "F.SilkS")
		)
		(fp_line
			(start -1.651 -1.778)
			(end -1.651 1.778)
			(stroke
				(width 0.1524)
				(type default)
			)
			(layer "F.SilkS")
		)
		(fp_poly
			(pts
				(xy -1.778 1.8796) (xy -1.778 -1.8796) (xy 1.778 -1.8796) (xy 1.778 1.8796)
			)
			(stroke
				(width 0)
				(type default)
			)
			(fill no)
			(layer "F.CrtYd")
		)
		(fp_poly
			(pts
				(xy -1.778 1.8796) (xy -1.778 -1.8796) (xy 1.778 -1.8796) (xy 1.778 1.8796)
			)
			(stroke
				(width 0)
				(type default)
			)
			(fill no)
			(layer "F.Fab")
		)
		(pad "D" smd custom
			(at 0 -0.9525 180)
			(size 0.1905 0.1905)
			(layers "F.Cu" "F.Mask" "F.Paste")
			(net "DRAWER_CLOSED_N")
			(options
				(clearance outline)
				(anchor circle)
			)
			(primitives
				(gr_poly
					(pts
						(arc
							(start -0.1778 0.5715)
							(mid -0.321484 0.511984)
							(end -0.381 0.3683)
						)
						(arc
							(start -0.381 -0.3683)
							(mid -0.321484 -0.511984)
							(end -0.1778 -0.5715)
						)
						(arc
							(start 0.1778 -0.5715)
							(mid 0.321484 -0.511984)
							(end 0.381 -0.3683)
						)
						(arc
							(start 0.381 0.3683)
							(mid 0.321484 0.511984)
							(end 0.1778 0.5715)
						)
					)
					(width 0)
					(fill yes)
				)
			)
		)
		(pad "G" smd custom
			(at -0.98425 0.9525 180)
			(size 0.1905 0.1905)
			(layers "F.Cu" "F.Mask" "F.Paste")
			(net "DRAWER_MOSFET_G")
			(options
				(clearance outline)
				(anchor circle)
			)
			(primitives
				(gr_poly
					(pts
						(arc
							(start -0.1778 0.5715)
							(mid -0.321484 0.511984)
							(end -0.381 0.3683)
						)
						(arc
							(start -0.381 -0.3683)
							(mid -0.321484 -0.511984)
							(end -0.1778 -0.5715)
						)
						(arc
							(start 0.1778 -0.5715)
							(mid 0.321484 -0.511984)
							(end 0.381 -0.3683)
						)
						(arc
							(start 0.381 0.3683)
							(mid 0.321484 0.511984)
							(end 0.1778 0.5715)
						)
					)
					(width 0)
					(fill yes)
				)
			)
		)
		(pad "S" smd custom
			(at 0.98425 0.9525 180)
			(size 0.1905 0.1905)
			(layers "F.Cu" "F.Mask" "F.Paste")
			(net "GND")
			(options
				(clearance outline)
				(anchor circle)
			)
			(primitives
				(gr_poly
					(pts
						(arc
							(start -0.1778 0.5715)
							(mid -0.321484 0.511984)
							(end -0.381 0.3683)
						)
						(arc
							(start -0.381 -0.3683)
							(mid -0.321484 -0.511984)
							(end -0.1778 -0.5715)
						)
						(arc
							(start 0.1778 -0.5715)
							(mid 0.321484 -0.511984)
							(end 0.381 -0.3683)
						)
						(arc
							(start 0.381 0.3683)
							(mid 0.321484 0.511984)
							(end 0.1778 0.5715)
						)
					)
					(width 0)
					(fill yes)
				)
			)
		)
	)
	(footprint ""
		(layer "F.Cu")
		(at 479.298 -275.463 180)
		(property "Reference" "C180"
			(at 0 0 180)
			(layer "F.SilkS")
			(hide yes)
			(effects
				(font
					(size 1.27 1.27)
				)
			)
		)
		(property "Value" "SC1U25V3KX-GP"
			(at 0 -2.8194 180)
			(unlocked yes)
			(layer "F.Fab")
			(hide yes)
			(effects
				(font
					(size 1.016 1.016)
					(thickness 0.1524)
				)
			)
		)
		(property "Device Type" "C603H36"
			(at 0 -4.3434 180)
			(unlocked yes)
			(layer "F.Fab")
			(hide yes)
			(effects
				(font
					(size 1.016 1.016)
					(thickness 0.1524)
				)
			)
		)
		(duplicate_pad_numbers_are_jumpers no)
		(fp_line
			(start 0.508 0)
			(end -0.508 0)
			(stroke
				(width 0.2032)
				(type default)
			)
			(layer "F.SilkS")
		)
		(fp_rect
			(start -0.5842 1.3335)
			(end 0.5842 -1.3335)
			(stroke
				(width 0)
				(type default)
			)
			(fill no)
			(layer "F.CrtYd")
		)
		(fp_rect
			(start -0.5842 1.3335)
			(end 0.5842 -1.3335)
			(stroke
				(width 0)
				(type default)
			)
			(fill no)
			(layer "F.Fab")
		)
		(pad "1" smd custom
			(at 0 -0.762 180)
			(size 0.2159 0.2159)
			(layers "F.Cu" "F.Mask" "F.Paste")
			(net "P12V_HDD11")
			(options
				(clearance outline)
				(anchor circle)
			)
			(primitives
				(gr_poly
					(pts
						(arc
							(start -0.3302 -0.4318)
							(mid -0.402042 -0.402042)
							(end -0.4318 -0.3302)
						)
						(arc
							(start -0.4318 0.3302)
							(mid -0.402042 0.402042)
							(end -0.3302 0.4318)
						)
						(arc
							(start 0.3302 0.4318)
							(mid 0.402042 0.402042)
							(end 0.4318 0.3302)
						)
						(arc
							(start 0.4318 -0.3302)
							(mid 0.402042 -0.402042)
							(end 0.3302 -0.4318)
						)
					)
					(width 0)
					(fill yes)
				)
			)
		)
		(pad "2" smd custom
			(at 0 0.762 180)
			(size 0.2159 0.2159)
			(layers "F.Cu" "F.Mask" "F.Paste")
			(net "GND")
			(options
				(clearance outline)
				(anchor circle)
			)
			(primitives
				(gr_poly
					(pts
						(arc
							(start -0.3302 -0.4318)
							(mid -0.402042 -0.402042)
							(end -0.4318 -0.3302)
						)
						(arc
							(start -0.4318 0.3302)
							(mid -0.402042 0.402042)
							(end -0.3302 0.4318)
						)
						(arc
							(start 0.3302 0.4318)
							(mid 0.402042 0.402042)
							(end 0.4318 0.3302)
						)
						(arc
							(start 0.4318 -0.3302)
							(mid 0.402042 -0.402042)
							(end 0.3302 -0.4318)
						)
					)
					(width 0)
					(fill yes)
				)
			)
		)
	)
	(footprint ""
		(layer "F.Cu")
		(at 362.966 -274.955 180)
		(property "Reference" "C126"
			(at 0 0 180)
			(layer "F.SilkS")
			(hide yes)
			(effects
				(font
					(size 1.27 1.27)
				)
			)
		)
		(property "Value" "SC4D7U25V5KX-1-GP"
			(at -0.0762 -6.1214 180)
			(unlocked yes)
			(layer "F.Fab")
			(hide yes)
			(effects
				(font
					(size 1.016 1.016)
					(thickness 0.1524)
				)
			)
		)
		(property "Device Type" "C805H58"
			(at -0.0762 -8.1534 180)
			(unlocked yes)
			(layer "F.Fab")
			(hide yes)
			(effects
				(font
					(size 1.016 1.016)
					(thickness 0.1524)
				)
			)
		)
		(duplicate_pad_numbers_are_jumpers no)
		(fp_line
			(start 0.635 0)
			(end -0.635 0)
			(stroke
				(width 0.508)
				(type default)
			)
			(layer "F.SilkS")
		)
		(fp_rect
			(start -0.9652 1.778)
			(end 0.9652 -1.778)
			(stroke
				(width 0)
				(type default)
			)
			(fill no)
			(layer "F.CrtYd")
		)
		(fp_poly
			(pts
				(xy -0.9652 -1.778) (xy 0.9652 -1.778) (xy 0.9652 1.778) (xy -0.9652 1.778)
			)
			(stroke
				(width 0)
				(type default)
			)
			(fill no)
			(layer "F.Fab")
		)
		(pad "1" smd rect
			(at 0 -0.9652 180)
			(size 1.397 1.143)
			(layers "F.Cu" "F.Mask" "F.Paste")
			(net "P12V_HDD7")
		)
		(pad "2" smd rect
			(at 0 0.9652 180)
			(size 1.397 1.143)
			(layers "F.Cu" "F.Mask" "F.Paste")
			(net "GND")
		)
	)
	(footprint ""
		(layer "F.Cu")
		(at 146.939 -141.224 180)
		(property "Reference" "Q70"
			(at 0 0 180)
			(layer "F.SilkS")
			(hide yes)
			(effects
				(font
					(size 1.27 1.27)
				)
			)
		)
		(property "Value" "AO4406AL-GP"
			(at -3.707384 -1.5367 180)
			(unlocked yes)
			(layer "F.Fab")
			(hide yes)
			(effects
				(font
					(size 1.016 1.016)
					(thickness 0.1524)
				)
			)
		)
		(property "Device Type" "SOIC8H69"
			(at -3.707384 -3.0607 180)
			(unlocked yes)
			(layer "F.Fab")
			(hide yes)
			(effects
				(font
					(size 1.016 1.016)
					(thickness 0.1524)
				)
			)
		)
		(duplicate_pad_numbers_are_jumpers no)
		(fp_line
			(start 2.1336 1.4224)
			(end 2.1336 -1.4224)
			(stroke
				(width 0.1524)
				(type default)
			)
			(layer "F.SilkS")
		)
		(fp_line
			(start 2.1336 -1.4224)
			(end -2.7432 -1.4224)
			(stroke
				(width 0.1524)
				(type default)
			)
			(layer "F.SilkS")
		)
		(fp_line
			(start -2.1844 -0.0508)
			(end -2.7178 0.508)
			(stroke
				(width 0.1524)
				(type default)
			)
			(layer "F.SilkS")
		)
		(fp_line
			(start -2.6289 3.4417)
			(end -2.6289 1.4732)
			(stroke
				(width 0.381)
				(type default)
			)
			(layer "F.SilkS")
		)
		(fp_line
			(start -2.7178 -0.508)
			(end -2.1844 -0.0508)
			(stroke
				(width 0.1524)
				(type default)
			)
			(layer "F.SilkS")
		)
		(fp_line
			(start -2.7432 1.4224)
			(end 2.1336 1.4224)
			(stroke
				(width 0.1524)
				(type default)
			)
			(layer "F.SilkS")
		)
		(fp_line
			(start -2.7432 1.4224)
			(end -2.6416 1.4224)
			(stroke
				(width 0.1524)
				(type default)
			)
			(layer "F.SilkS")
		)
		(fp_line
			(start -2.7432 -1.4224)
			(end -2.7432 1.4224)
			(stroke
				(width 0.1524)
				(type default)
			)
			(layer "F.SilkS")
		)
		(fp_poly
			(pts
				(xy -2.2098 -1.4224) (xy -2.2098 1.4224) (xy 2.2098 1.4224) (xy 2.2098 -1.4224)
			)
			(stroke
				(width 0)
				(type default)
			)
			(fill yes)
			(layer "F.SilkS")
		)
		(fp_rect
			(start -2.450084 2.999994)
			(end 2.450084 -2.999994)
			(stroke
				(width 0)
				(type default)
			)
			(fill no)
			(layer "F.CrtYd")
		)
		(fp_poly
			(pts
				(xy -2.8194 3.6322) (xy -2.8194 -3.6322) (xy 2.8194 -3.6322) (xy 2.8194 1.18364) (xy 2.450084 1.18364)
				(xy 2.450084 -2.999994) (xy -2.450084 -2.999994) (xy -2.450084 2.999994) (xy 2.450084 2.999994)
				(xy 2.450084 1.18618) (xy 2.8194 1.18618) (xy 2.8194 3.6322)
			)
			(stroke
				(width 0)
				(type default)
			)
			(fill no)
			(layer "F.CrtYd")
		)
		(fp_rect
			(start -2.8194 3.6322)
			(end 2.8194 -3.6322)
			(stroke
				(width 0)
				(type default)
			)
			(fill no)
			(layer "F.Fab")
		)
		(pad "1" smd rect
			(at -1.905 2.54 180)
			(size 0.635 1.651)
			(layers "F.Cu" "F.Mask" "F.Paste")
			(net "P5V_HDD16")
		)
		(pad "2" smd rect
			(at -0.635 2.54 180)
			(size 0.635 1.651)
			(layers "F.Cu" "F.Mask" "F.Paste")
			(net "P5V_HDD16")
		)
		(pad "3" smd rect
			(at 0.635 2.54 180)
			(size 0.635 1.651)
			(layers "F.Cu" "F.Mask" "F.Paste")
			(net "P5V_HDD16")
		)
		(pad "4" smd rect
			(at 1.905 2.54 180)
			(size 0.635 1.651)
			(layers "F.Cu" "F.Mask" "F.Paste")
			(net "SW_HDD_P16")
		)
		(pad "5" smd rect
			(at 1.905 -2.54 180)
			(size 0.635 1.651)
			(layers "F.Cu" "F.Mask" "F.Paste")
			(net "P5V_B_2")
		)
		(pad "6" smd rect
			(at 0.635 -2.54 180)
			(size 0.635 1.651)
			(layers "F.Cu" "F.Mask" "F.Paste")
			(net "P5V_B_2")
		)
		(pad "7" smd rect
			(at -0.635 -2.54 180)
			(size 0.635 1.651)
			(layers "F.Cu" "F.Mask" "F.Paste")
			(net "P5V_B_2")
		)
		(pad "8" smd rect
			(at -1.905 -2.54 180)
			(size 0.635 1.651)
			(layers "F.Cu" "F.Mask" "F.Paste")
			(net "P5V_B_2")
		)
	)
	(footprint ""
		(layer "F.Cu")
		(at 477.0882 -268.2494)
		(property "Reference" "TP76"
			(at 0 0 0)
			(layer "F.SilkS")
			(hide yes)
			(effects
				(font
					(size 1.27 1.27)
				)
			)
		)
		(property "Value" "*"
			(at -0.0508 -1.6764 0)
			(unlocked yes)
			(layer "F.Fab")
			(hide yes)
			(effects
				(font
					(size 1.016 1.016)
					(thickness 0.1524)
				)
			)
		)
		(property "Device Type" "TPAD32"
			(at -0.0508 -3.2004 0)
			(unlocked yes)
			(layer "F.Fab")
			(hide yes)
			(effects
				(font
					(size 1.016 1.016)
					(thickness 0.1524)
				)
			)
		)
		(duplicate_pad_numbers_are_jumpers no)
		(fp_poly
			(pts
				(arc
					(start 0.4064 0)
					(mid -0.4064 0)
					(end 0.4064 0)
				)
			)
			(stroke
				(width 0)
				(type default)
			)
			(fill no)
			(layer "F.CrtYd")
		)
		(fp_poly
			(pts
				(arc
					(start 0.7112 0)
					(mid -0.7112 0)
					(end 0.7112 0)
				)
			)
			(stroke
				(width 0)
				(type default)
			)
			(fill no)
			(layer "F.Fab")
		)
		(pad "1" smd circle
			(at 0 0)
			(size 0.8128 0.8128)
			(layers "F.Cu" "F.Mask" "F.Paste")
			(net "ACT_HDD_11")
		)
	)
	(footprint ""
		(layer "F.Cu")
		(at 300.709076 -340.812882 180)
		(property "Reference" "R102"
			(at 0 0 180)
			(layer "F.SilkS")
			(hide yes)
			(effects
				(font
					(size 1.27 1.27)
				)
			)
		)
		(property "Value" "100KR2F-L1-GP"
			(at 0.064008 -3.993896 180)
			(unlocked yes)
			(layer "F.Fab")
			(hide yes)
			(effects
				(font
					(size 1.016 1.016)
					(thickness 0.1524)
				)
			)
		)
		(property "Device Type" "R402H16"
			(at 0.064008 -5.517896 180)
			(unlocked yes)
			(layer "F.Fab")
			(hide yes)
			(effects
				(font
					(size 1.016 1.016)
					(thickness 0.1524)
				)
			)
		)
		(duplicate_pad_numbers_are_jumpers no)
		(fp_line
			(start 0.508 -0.9398)
			(end -0.508 -0.9398)
			(stroke
				(width 0.1524)
				(type default)
			)
			(layer "F.SilkS")
		)
		(fp_line
			(start -0.508 -0.9398)
			(end -0.508 0.9398)
			(stroke
				(width 0.1524)
				(type default)
			)
			(layer "F.SilkS")
		)
		(fp_rect
			(start -0.508 0.9398)
			(end 0.508 -0.9398)
			(stroke
				(width 0)
				(type default)
			)
			(fill no)
			(layer "F.CrtYd")
		)
		(fp_rect
			(start -0.508 0.9398)
			(end 0.508 -0.9398)
			(stroke
				(width 0)
				(type default)
			)
			(fill no)
			(layer "F.Fab")
		)
		(pad "1" smd custom
			(at 0 -0.4445 180)
			(size 0.1397 0.1397)
			(layers "F.Cu" "F.Mask" "F.Paste")
			(net "PWM_SCC_B_ZONE_C")
			(options
				(clearance outline)
				(anchor circle)
			)
			(primitives
				(gr_poly
					(pts
						(arc
							(start -0.1778 -0.2794)
							(mid -0.249642 -0.249642)
							(end -0.2794 -0.1778)
						)
						(arc
							(start -0.2794 0.1778)
							(mid -0.249642 0.249642)
							(end -0.1778 0.2794)
						)
						(arc
							(start 0.1778 0.2794)
							(mid 0.249642 0.249642)
							(end 0.2794 0.1778)
						)
						(arc
							(start 0.2794 -0.1778)
							(mid 0.249642 -0.249642)
							(end 0.1778 -0.2794)
						)
					)
					(width 0)
					(fill yes)
				)
			)
		)
		(pad "2" smd custom
			(at 0 0.4445 180)
			(size 0.1397 0.1397)
			(layers "F.Cu" "F.Mask" "F.Paste")
			(net "GND")
			(options
				(clearance outline)
				(anchor circle)
			)
			(primitives
				(gr_poly
					(pts
						(arc
							(start -0.1778 -0.2794)
							(mid -0.249642 -0.249642)
							(end -0.2794 -0.1778)
						)
						(arc
							(start -0.2794 0.1778)
							(mid -0.249642 0.249642)
							(end -0.1778 0.2794)
						)
						(arc
							(start 0.1778 0.2794)
							(mid 0.249642 0.249642)
							(end 0.2794 0.1778)
						)
						(arc
							(start 0.2794 -0.1778)
							(mid 0.249642 -0.249642)
							(end 0.1778 -0.2794)
						)
					)
					(width 0)
					(fill yes)
				)
			)
		)
	)
)
